(kicad_pcb
	(version 20260206)
	(generator "pcbnew")
	(generator_version "10.0")
	(general
		(thickness 1.6)
		(legacy_teardrops no)
	)
	(paper "A4")
	(title_block
		(title "03242023_DA0F0TMBIJ0_F0T_Motherboard_J_brd_V01_OCP.brd")
		(comment 1 "Grand Teton / footprints 6092-6098 of 6105")
	)
	(layers
		(0 "F.Cu" signal "TOP")
		(4 "In1.Cu" signal "GND")
		(6 "In2.Cu" signal "IN1")
		(8 "In3.Cu" signal "GND1")
		(10 "In4.Cu" signal "IN2")
		(12 "In5.Cu" signal "GND2")
		(14 "In6.Cu" signal "IN3")
		(16 "In7.Cu" signal "GND3")
		(18 "In8.Cu" signal "VCC")
		(20 "In9.Cu" signal "VCC1")
		(22 "In10.Cu" signal "GND4")
		(24 "In11.Cu" signal "IN4")
		(26 "In12.Cu" signal "GND5")
		(28 "In13.Cu" signal "IN5")
		(30 "In14.Cu" signal "GND6")
		(32 "In15.Cu" signal "IN6")
		(34 "In16.Cu" signal "GND7")
		(2 "B.Cu" signal "BOTTOM")
		(9 "F.Adhes" user "F.Adhesive")
		(11 "B.Adhes" user "B.Adhesive")
		(13 "F.Paste" user "Package Geometry/Pastemask Top")
		(15 "B.Paste" user "Package Geometry/Pastemask Bottom")
		(5 "F.SilkS" user "Ref Des/Silkscreen Top")
		(7 "B.SilkS" user "Ref Des/Silkscreen Bottom")
		(1 "F.Mask" user "Board Geometry/Soldermask Top")
		(3 "B.Mask" user "Board Geometry/Soldermask Bottom")
		(17 "Dwgs.User" user "User.Drawings")
		(19 "Cmts.User" user "User.Comments")
		(21 "Eco1.User" user "User.Eco1")
		(23 "Eco2.User" user "User.Eco2")
		(25 "Edge.Cuts" user "Board Geometry/Outline")
		(27 "Margin" user)
		(31 "F.CrtYd" user "Package Geometry/Place Bound Top")
		(29 "B.CrtYd" user "Package Geometry/Place Bound Bottom")
		(35 "F.Fab" user "Ref Des/Assembly Top")
		(33 "B.Fab" user "Ref Des/Assembly Bottom")
	)
	(footprint ""
		(layer "B.Cu")
		(at 329.170538 -184.58815 -90)
		(property "Reference" "R296"
			(at 0 0 90)
			(layer "B.SilkS")
			(hide yes)
			(effects
				(font
					(size 1.27 1.27)
				)
				(justify mirror)
			)
		)
		(property "Value" ""
			(at 0 0 90)
			(layer "B.Fab")
			(effects
				(font
					(size 1.27 1.27)
				)
				(justify mirror)
			)
		)
		(duplicate_pad_numbers_are_jumpers no)
		(fp_line
			(start -0.7874 0.4064)
			(end 0.7874 0.4064)
			(stroke
				(width 0.1524)
				(type default)
			)
			(layer "B.SilkS")
		)
		(fp_line
			(start 0.7874 0.4064)
			(end 0.7874 -0.4064)
			(stroke
				(width 0.1524)
				(type default)
			)
			(layer "B.SilkS")
		)
		(fp_line
			(start -0.7874 -0.4064)
			(end -0.7874 0.4064)
			(stroke
				(width 0.1524)
				(type default)
			)
			(layer "B.SilkS")
		)
		(fp_line
			(start 0.7874 -0.4064)
			(end -0.7874 -0.4064)
			(stroke
				(width 0.1524)
				(type default)
			)
			(layer "B.SilkS")
		)
		(fp_line
			(start -0.67945 0.3048)
			(end -0.120396 0.3048)
			(stroke
				(width 0.1)
				(type default)
			)
			(layer "B.Fab")
		)
		(fp_line
			(start -0.120396 0.3048)
			(end -0.120396 0.2794)
			(stroke
				(width 0.1)
				(type default)
			)
			(layer "B.Fab")
		)
		(fp_line
			(start 0.12065 0.3048)
			(end 0.67945 0.3048)
			(stroke
				(width 0.1)
				(type default)
			)
			(layer "B.Fab")
		)
		(fp_line
			(start 0.67945 0.3048)
			(end 0.67945 -0.305054)
			(stroke
				(width 0.1)
				(type default)
			)
			(layer "B.Fab")
		)
		(fp_line
			(start -0.120396 0.2794)
			(end 0.12065 0.2794)
			(stroke
				(width 0.1)
				(type default)
			)
			(layer "B.Fab")
		)
		(fp_line
			(start 0.12065 0.2794)
			(end 0.12065 0.3048)
			(stroke
				(width 0.1)
				(type default)
			)
			(layer "B.Fab")
		)
		(fp_line
			(start -0.12065 -0.2794)
			(end -0.12065 -0.3048)
			(stroke
				(width 0.1)
				(type default)
			)
			(layer "B.Fab")
		)
		(fp_line
			(start 0.12065 -0.2794)
			(end -0.12065 -0.2794)
			(stroke
				(width 0.1)
				(type default)
			)
			(layer "B.Fab")
		)
		(fp_line
			(start -0.67945 -0.3048)
			(end -0.67945 0.3048)
			(stroke
				(width 0.1)
				(type default)
			)
			(layer "B.Fab")
		)
		(fp_line
			(start -0.12065 -0.3048)
			(end -0.67945 -0.3048)
			(stroke
				(width 0.1)
				(type default)
			)
			(layer "B.Fab")
		)
		(fp_line
			(start 0.12065 -0.305054)
			(end 0.12065 -0.2794)
			(stroke
				(width 0.1)
				(type default)
			)
			(layer "B.Fab")
		)
		(fp_line
			(start 0.67945 -0.305054)
			(end 0.12065 -0.305054)
			(stroke
				(width 0.1)
				(type default)
			)
			(layer "B.Fab")
		)
		(pad "1" smd circle
			(at 0.40005 0 90)
			(size 0 0)
			(layers "B.Cu" "B.Mask" "B.Paste")
			(net "PVNN_TERM_CPU0")
		)
		(pad "2" smd circle
			(at -0.40005 0 90)
			(size 0 0)
			(layers "B.Cu" "B.Mask" "B.Paste")
			(net "H_CPU_CATERR_LVC1_R_N")
		)
	)
	(footprint ""
		(layer "B.Cu")
		(at 130.761486 -337.145884 90)
		(property "Reference" "PC512_P1_5"
			(at 0 0 90)
			(layer "B.SilkS")
			(hide yes)
			(effects
				(font
					(size 1.27 1.27)
				)
				(justify mirror)
			)
		)
		(property "Value" ""
			(at 0 0 90)
			(layer "B.Fab")
			(effects
				(font
					(size 1.27 1.27)
				)
				(justify mirror)
			)
		)
		(duplicate_pad_numbers_are_jumpers no)
		(fp_line
			(start 1.524 -0.762)
			(end -1.524 -0.762)
			(stroke
				(width 0.1524)
				(type default)
			)
			(layer "B.SilkS")
		)
		(fp_line
			(start -1.524 -0.762)
			(end -1.524 0.762)
			(stroke
				(width 0.1524)
				(type default)
			)
			(layer "B.SilkS")
		)
		(fp_line
			(start 1.524 0.762)
			(end 1.524 -0.762)
			(stroke
				(width 0.1524)
				(type default)
			)
			(layer "B.SilkS")
		)
		(fp_line
			(start -1.524 0.762)
			(end 1.524 0.762)
			(stroke
				(width 0.1524)
				(type default)
			)
			(layer "B.SilkS")
		)
		(fp_line
			(start 1.1049 -0.724916)
			(end 1.1049 0.724916)
			(stroke
				(width 0.1)
				(type default)
			)
			(layer "B.Fab")
		)
		(fp_line
			(start -1.1049 -0.724916)
			(end 1.1049 -0.724916)
			(stroke
				(width 0.1)
				(type default)
			)
			(layer "B.Fab")
		)
		(fp_line
			(start 1.1049 0.724916)
			(end -1.1049 0.724916)
			(stroke
				(width 0.1)
				(type default)
			)
			(layer "B.Fab")
		)
		(fp_line
			(start -1.1049 0.724916)
			(end -1.1049 -0.724916)
			(stroke
				(width 0.1)
				(type default)
			)
			(layer "B.Fab")
		)
		(pad "1" smd rect
			(at 0.889 0 90)
			(size 1.016 1.27)
			(layers "B.Cu" "B.Mask" "B.Paste")
			(net "SW_P12V_PVCCIN_CPU1_FLT")
		)
		(pad "2" smd rect
			(at -0.889 0 90)
			(size 1.016 1.27)
			(layers "B.Cu" "B.Mask" "B.Paste")
			(net "GND")
		)
	)
	(footprint ""
		(layer "B.Cu")
		(at 448.549014 -321.549776 -90)
		(property "Reference" "C39"
			(at 0 0 90)
			(layer "B.SilkS")
			(hide yes)
			(effects
				(font
					(size 1.27 1.27)
				)
				(justify mirror)
			)
		)
		(property "Value" ""
			(at 0 0 90)
			(layer "B.Fab")
			(effects
				(font
					(size 1.27 1.27)
				)
				(justify mirror)
			)
		)
		(duplicate_pad_numbers_are_jumpers no)
		(fp_line
			(start -1.524 0.762)
			(end 1.524 0.762)
			(stroke
				(width 0.1524)
				(type default)
			)
			(layer "B.SilkS")
		)
		(fp_line
			(start 1.524 0.762)
			(end 1.524 -0.762)
			(stroke
				(width 0.1524)
				(type default)
			)
			(layer "B.SilkS")
		)
		(fp_line
			(start -1.524 -0.762)
			(end -1.524 0.762)
			(stroke
				(width 0.1524)
				(type default)
			)
			(layer "B.SilkS")
		)
		(fp_line
			(start 1.524 -0.762)
			(end -1.524 -0.762)
			(stroke
				(width 0.1524)
				(type default)
			)
			(layer "B.SilkS")
		)
		(fp_line
			(start -1.1049 0.724916)
			(end -1.1049 -0.724916)
			(stroke
				(width 0.1)
				(type default)
			)
			(layer "B.Fab")
		)
		(fp_line
			(start 1.1049 0.724916)
			(end -1.1049 0.724916)
			(stroke
				(width 0.1)
				(type default)
			)
			(layer "B.Fab")
		)
		(fp_line
			(start -1.1049 -0.724916)
			(end 1.1049 -0.724916)
			(stroke
				(width 0.1)
				(type default)
			)
			(layer "B.Fab")
		)
		(fp_line
			(start 1.1049 -0.724916)
			(end 1.1049 0.724916)
			(stroke
				(width 0.1)
				(type default)
			)
			(layer "B.Fab")
		)
		(pad "1" smd rect
			(at 0.889 0 270)
			(size 1.016 1.27)
			(layers "B.Cu" "B.Mask" "B.Paste")
			(net "P12V_S3_AUX_CPU0_NVDIMM")
		)
		(pad "2" smd rect
			(at -0.889 0 270)
			(size 1.016 1.27)
			(layers "B.Cu" "B.Mask" "B.Paste")
			(net "GND")
		)
	)
	(footprint ""
		(layer "B.Cu")
		(at 193.60388 -106.225848 180)
		(property "Reference" "R1312"
			(at 0 0 0)
			(layer "B.SilkS")
			(hide yes)
			(effects
				(font
					(size 1.27 1.27)
				)
				(justify mirror)
			)
		)
		(property "Value" ""
			(at 0 0 0)
			(layer "B.Fab")
			(effects
				(font
					(size 1.27 1.27)
				)
				(justify mirror)
			)
		)
		(duplicate_pad_numbers_are_jumpers no)
		(fp_line
			(start 0.7874 0.4064)
			(end 0.7874 -0.4064)
			(stroke
				(width 0.1524)
				(type default)
			)
			(layer "B.SilkS")
		)
		(fp_line
			(start 0.7874 -0.4064)
			(end -0.7874 -0.4064)
			(stroke
				(width 0.1524)
				(type default)
			)
			(layer "B.SilkS")
		)
		(fp_line
			(start -0.7874 0.4064)
			(end 0.7874 0.4064)
			(stroke
				(width 0.1524)
				(type default)
			)
			(layer "B.SilkS")
		)
		(fp_line
			(start -0.7874 -0.4064)
			(end -0.7874 0.4064)
			(stroke
				(width 0.1524)
				(type default)
			)
			(layer "B.SilkS")
		)
		(fp_line
			(start 0.67945 0.3048)
			(end 0.67945 -0.305054)
			(stroke
				(width 0.1)
				(type default)
			)
			(layer "B.Fab")
		)
		(fp_line
			(start 0.67945 -0.305054)
			(end 0.12065 -0.305054)
			(stroke
				(width 0.1)
				(type default)
			)
			(layer "B.Fab")
		)
		(fp_line
			(start 0.12065 0.3048)
			(end 0.67945 0.3048)
			(stroke
				(width 0.1)
				(type default)
			)
			(layer "B.Fab")
		)
		(fp_line
			(start 0.12065 0.2794)
			(end 0.12065 0.3048)
			(stroke
				(width 0.1)
				(type default)
			)
			(layer "B.Fab")
		)
		(fp_line
			(start 0.12065 -0.2794)
			(end -0.12065 -0.2794)
			(stroke
				(width 0.1)
				(type default)
			)
			(layer "B.Fab")
		)
		(fp_line
			(start 0.12065 -0.305054)
			(end 0.12065 -0.2794)
			(stroke
				(width 0.1)
				(type default)
			)
			(layer "B.Fab")
		)
		(fp_line
			(start -0.120396 0.3048)
			(end -0.120396 0.2794)
			(stroke
				(width 0.1)
				(type default)
			)
			(layer "B.Fab")
		)
		(fp_line
			(start -0.120396 0.2794)
			(end 0.12065 0.2794)
			(stroke
				(width 0.1)
				(type default)
			)
			(layer "B.Fab")
		)
		(fp_line
			(start -0.12065 -0.2794)
			(end -0.12065 -0.3048)
			(stroke
				(width 0.1)
				(type default)
			)
			(layer "B.Fab")
		)
		(fp_line
			(start -0.12065 -0.3048)
			(end -0.67945 -0.3048)
			(stroke
				(width 0.1)
				(type default)
			)
			(layer "B.Fab")
		)
		(fp_line
			(start -0.67945 0.3048)
			(end -0.120396 0.3048)
			(stroke
				(width 0.1)
				(type default)
			)
			(layer "B.Fab")
		)
		(fp_line
			(start -0.67945 -0.3048)
			(end -0.67945 0.3048)
			(stroke
				(width 0.1)
				(type default)
			)
			(layer "B.Fab")
		)
		(pad "1" smd circle
			(at 0.40005 0)
			(size 0 0)
			(layers "B.Cu" "B.Mask" "B.Paste")
			(net "FM_RST_PERST_BIT2")
		)
		(pad "2" smd circle
			(at -0.40005 0)
			(size 0 0)
			(layers "B.Cu" "B.Mask" "B.Paste")
			(net "GND")
		)
	)
	(footprint ""
		(layer "B.Cu")
		(at 304.697638 -192.450466 90)
		(property "Reference" "R328"
			(at 0 0 90)
			(layer "B.SilkS")
			(hide yes)
			(effects
				(font
					(size 1.27 1.27)
				)
				(justify mirror)
			)
		)
		(property "Value" ""
			(at 0 0 90)
			(layer "B.Fab")
			(effects
				(font
					(size 1.27 1.27)
				)
				(justify mirror)
			)
		)
		(duplicate_pad_numbers_are_jumpers no)
		(fp_line
			(start 0.7874 -0.4064)
			(end -0.7874 -0.4064)
			(stroke
				(width 0.1524)
				(type default)
			)
			(layer "B.SilkS")
		)
		(fp_line
			(start -0.7874 -0.4064)
			(end -0.7874 0.4064)
			(stroke
				(width 0.1524)
				(type default)
			)
			(layer "B.SilkS")
		)
		(fp_line
			(start 0.7874 0.4064)
			(end 0.7874 -0.4064)
			(stroke
				(width 0.1524)
				(type default)
			)
			(layer "B.SilkS")
		)
		(fp_line
			(start -0.7874 0.4064)
			(end 0.7874 0.4064)
			(stroke
				(width 0.1524)
				(type default)
			)
			(layer "B.SilkS")
		)
		(fp_line
			(start 0.67945 -0.305054)
			(end 0.12065 -0.305054)
			(stroke
				(width 0.1)
				(type default)
			)
			(layer "B.Fab")
		)
		(fp_line
			(start 0.12065 -0.305054)
			(end 0.12065 -0.2794)
			(stroke
				(width 0.1)
				(type default)
			)
			(layer "B.Fab")
		)
		(fp_line
			(start -0.12065 -0.3048)
			(end -0.67945 -0.3048)
			(stroke
				(width 0.1)
				(type default)
			)
			(layer "B.Fab")
		)
		(fp_line
			(start -0.67945 -0.3048)
			(end -0.67945 0.3048)
			(stroke
				(width 0.1)
				(type default)
			)
			(layer "B.Fab")
		)
		(fp_line
			(start 0.12065 -0.2794)
			(end -0.12065 -0.2794)
			(stroke
				(width 0.1)
				(type default)
			)
			(layer "B.Fab")
		)
		(fp_line
			(start -0.12065 -0.2794)
			(end -0.12065 -0.3048)
			(stroke
				(width 0.1)
				(type default)
			)
			(layer "B.Fab")
		)
		(fp_line
			(start 0.12065 0.2794)
			(end 0.12065 0.3048)
			(stroke
				(width 0.1)
				(type default)
			)
			(layer "B.Fab")
		)
		(fp_line
			(start -0.120396 0.2794)
			(end 0.12065 0.2794)
			(stroke
				(width 0.1)
				(type default)
			)
			(layer "B.Fab")
		)
		(fp_line
			(start 0.67945 0.3048)
			(end 0.67945 -0.305054)
			(stroke
				(width 0.1)
				(type default)
			)
			(layer "B.Fab")
		)
		(fp_line
			(start 0.12065 0.3048)
			(end 0.67945 0.3048)
			(stroke
				(width 0.1)
				(type default)
			)
			(layer "B.Fab")
		)
		(fp_line
			(start -0.120396 0.3048)
			(end -0.120396 0.2794)
			(stroke
				(width 0.1)
				(type default)
			)
			(layer "B.Fab")
		)
		(fp_line
			(start -0.67945 0.3048)
			(end -0.120396 0.3048)
			(stroke
				(width 0.1)
				(type default)
			)
			(layer "B.Fab")
		)
		(pad "1" smd circle
			(at 0.40005 0 270)
			(size 0 0)
			(layers "B.Cu" "B.Mask" "B.Paste")
			(net "SVID_DIO0_CPU0_R")
		)
		(pad "2" smd circle
			(at -0.40005 0 270)
			(size 0 0)
			(layers "B.Cu" "B.Mask" "B.Paste")
			(net "PVNN_TERM_CPU0")
		)
	)
	(footprint ""
		(layer "B.Cu")
		(at 54.880002 -148.963634 180)
		(property "Reference" "PC451_P1_2"
			(at 0 0 0)
			(layer "B.SilkS")
			(hide yes)
			(effects
				(font
					(size 1.27 1.27)
				)
				(justify mirror)
			)
		)
		(property "Value" ""
			(at 0 0 0)
			(layer "B.Fab")
			(effects
				(font
					(size 1.27 1.27)
				)
				(justify mirror)
			)
		)
		(duplicate_pad_numbers_are_jumpers no)
		(fp_line
			(start 1.524 0.762)
			(end 1.524 -0.762)
			(stroke
				(width 0.1524)
				(type default)
			)
			(layer "B.SilkS")
		)
		(fp_line
			(start 1.524 -0.762)
			(end -1.524 -0.762)
			(stroke
				(width 0.1524)
				(type default)
			)
			(layer "B.SilkS")
		)
		(fp_line
			(start -1.524 0.762)
			(end 1.524 0.762)
			(stroke
				(width 0.1524)
				(type default)
			)
			(layer "B.SilkS")
		)
		(fp_line
			(start -1.524 -0.762)
			(end -1.524 0.762)
			(stroke
				(width 0.1524)
				(type default)
			)
			(layer "B.SilkS")
		)
		(fp_line
			(start 1.1049 0.724916)
			(end -1.1049 0.724916)
			(stroke
				(width 0.1)
				(type default)
			)
			(layer "B.Fab")
		)
		(fp_line
			(start 1.1049 -0.724916)
			(end 1.1049 0.724916)
			(stroke
				(width 0.1)
				(type default)
			)
			(layer "B.Fab")
		)
		(fp_line
			(start -1.1049 0.724916)
			(end -1.1049 -0.724916)
			(stroke
				(width 0.1)
				(type default)
			)
			(layer "B.Fab")
		)
		(fp_line
			(start -1.1049 -0.724916)
			(end 1.1049 -0.724916)
			(stroke
				(width 0.1)
				(type default)
			)
			(layer "B.Fab")
		)
		(pad "1" smd rect
			(at 0.889 0 180)
			(size 1.016 1.27)
			(layers "B.Cu" "B.Mask" "B.Paste")
			(net "SW_P12V_PVCCINFAON_CPU1_FLT")
		)
		(pad "2" smd rect
			(at -0.889 0 180)
			(size 1.016 1.27)
			(layers "B.Cu" "B.Mask" "B.Paste")
			(net "GND")
		)
	)
	(footprint ""
		(layer "B.Cu")
		(at 140.89888 -9.362948 -90)
		(property "Reference" "R1798"
			(at 0 0 90)
			(layer "B.SilkS")
			(hide yes)
			(effects
				(font
					(size 1.27 1.27)
				)
				(justify mirror)
			)
		)
		(property "Value" ""
			(at 0 0 90)
			(layer "B.Fab")
			(effects
				(font
					(size 1.27 1.27)
				)
				(justify mirror)
			)
		)
		(duplicate_pad_numbers_are_jumpers no)
		(fp_line
			(start -0.7874 0.4064)
			(end 0.7874 0.4064)
			(stroke
				(width 0.1524)
				(type default)
			)
			(layer "B.SilkS")
		)
		(fp_line
			(start 0.7874 0.4064)
			(end 0.7874 -0.4064)
			(stroke
				(width 0.1524)
				(type default)
			)
			(layer "B.SilkS")
		)
		(fp_line
			(start -0.7874 -0.4064)
			(end -0.7874 0.4064)
			(stroke
				(width 0.1524)
				(type default)
			)
			(layer "B.SilkS")
		)
		(fp_line
			(start 0.7874 -0.4064)
			(end -0.7874 -0.4064)
			(stroke
				(width 0.1524)
				(type default)
			)
			(layer "B.SilkS")
		)
		(fp_line
			(start -0.67945 0.3048)
			(end -0.120396 0.3048)
			(stroke
				(width 0.1)
				(type default)
			)
			(layer "B.Fab")
		)
		(fp_line
			(start -0.120396 0.3048)
			(end -0.120396 0.2794)
			(stroke
				(width 0.1)
				(type default)
			)
			(layer "B.Fab")
		)
		(fp_line
			(start 0.12065 0.3048)
			(end 0.67945 0.3048)
			(stroke
				(width 0.1)
				(type default)
			)
			(layer "B.Fab")
		)
		(fp_line
			(start 0.67945 0.3048)
			(end 0.67945 -0.305054)
			(stroke
				(width 0.1)
				(type default)
			)
			(layer "B.Fab")
		)
		(fp_line
			(start -0.120396 0.2794)
			(end 0.12065 0.2794)
			(stroke
				(width 0.1)
				(type default)
			)
			(layer "B.Fab")
		)
		(fp_line
			(start 0.12065 0.2794)
			(end 0.12065 0.3048)
			(stroke
				(width 0.1)
				(type default)
			)
			(layer "B.Fab")
		)
		(fp_line
			(start -0.12065 -0.2794)
			(end -0.12065 -0.3048)
			(stroke
				(width 0.1)
				(type default)
			)
			(layer "B.Fab")
		)
		(fp_line
			(start 0.12065 -0.2794)
			(end -0.12065 -0.2794)
			(stroke
				(width 0.1)
				(type default)
			)
			(layer "B.Fab")
		)
		(fp_line
			(start -0.67945 -0.3048)
			(end -0.67945 0.3048)
			(stroke
				(width 0.1)
				(type default)
			)
			(layer "B.Fab")
		)
		(fp_line
			(start -0.12065 -0.3048)
			(end -0.67945 -0.3048)
			(stroke
				(width 0.1)
				(type default)
			)
			(layer "B.Fab")
		)
		(fp_line
			(start 0.12065 -0.305054)
			(end 0.12065 -0.2794)
			(stroke
				(width 0.1)
				(type default)
			)
			(layer "B.Fab")
		)
		(fp_line
			(start 0.67945 -0.305054)
			(end 0.12065 -0.305054)
			(stroke
				(width 0.1)
				(type default)
			)
			(layer "B.Fab")
		)
		(pad "1" smd circle
			(at 0.40005 0 90)
			(size 0 0)
			(layers "B.Cu" "B.Mask" "B.Paste")
			(net "ROT_P1_RST_IND_N_R")
		)
		(pad "2" smd circle
			(at -0.40005 0 90)
			(size 0 0)
			(layers "B.Cu" "B.Mask" "B.Paste")
			(net "ROT_P1_RST_IND_N")
		)
	)
)
